(kicad_pcb
	(version 20260206)
	(generator "pcbnew")
	(generator_version "10.0")
	(general
		(thickness 1.6)
		(legacy_teardrops no)
	)
	(paper "A4")
	(title_block
		(title "Wiwynn_Tioga_Pass_MB.brd")
		(comment 1 "Tioga Pass / footprint 2167 of 4770 (J4G1), pads 124-243 of 291")
	)
	(layers
		(0 "F.Cu" signal "TOP")
		(4 "In1.Cu" signal "L2GND")
		(6 "In2.Cu" signal "L3")
		(8 "In3.Cu" signal "L4GND")
		(10 "In4.Cu" signal "L5")
		(12 "In5.Cu" signal "L6GND")
		(14 "In6.Cu" signal "L7VCC")
		(16 "In7.Cu" signal "L8VCC")
		(18 "In8.Cu" signal "L9GND")
		(20 "In9.Cu" signal "L10")
		(22 "In10.Cu" signal "L11GND")
		(24 "In11.Cu" signal "L12")
		(26 "In12.Cu" signal "L13GND")
		(2 "B.Cu" signal "BOTTOM")
		(9 "F.Adhes" user "F.Adhesive")
		(11 "B.Adhes" user "B.Adhesive")
		(13 "F.Paste" user "Package Geometry/Pastemask Top")
		(15 "B.Paste" user "Package Geometry/Pastemask Bottom")
		(5 "F.SilkS" user "Ref Des/Silkscreen Top")
		(7 "B.SilkS" user "Ref Des/Silkscreen Bottom")
		(1 "F.Mask" user "Board Geometry/Soldermask Top")
		(3 "B.Mask" user "Board Geometry/Soldermask Bottom")
		(17 "Dwgs.User" user "User.Drawings")
		(19 "Cmts.User" user "User.Comments")
		(21 "Eco1.User" user "User.Eco1")
		(23 "Eco2.User" user "User.Eco2")
		(25 "Edge.Cuts" user "Board Geometry/Outline")
		(27 "Margin" user)
		(31 "F.CrtYd" user "Package Geometry/Place Bound Top")
		(29 "B.CrtYd" user "Package Geometry/Place Bound Bottom")
		(35 "F.Fab" user "Ref Des/Assembly Top")
		(33 "B.Fab" user "Ref Des/Assembly Bottom")
	)
	(footprint ""
		(layer "F.Cu")
		(at 194.700398 -15.423642 90)
		(property "Reference" "J4G1"
			(at 9.060688 37.32911 0)
			(unlocked yes)
			(layer "F.SilkS")
			(effects
				(font
					(size 0.7874 0.5842)
					(thickness 0.1524)
				)
				(justify left)
			)
		)
		(property "Value" ""
			(at 0 0 90)
			(layer "F.Fab")
			(effects
				(font
					(size 1.27 1.27)
				)
			)
		)
		(duplicate_pad_numbers_are_jumpers no)
		(pad "121" smd rect
			(at 0 107.100116 90)
			(size 1.8034 0.508)
			(layers "F.Cu" "F.Mask" "F.Paste")
			(net "M_A_DQS_DP<15>")
		)
		(pad "122" smd rect
			(at 0 107.95 90)
			(size 1.8034 0.508)
			(layers "F.Cu" "F.Mask" "F.Paste")
			(net "M_A_DQS_DN<15>")
		)
		(pad "123" smd rect
			(at 0 108.799884 90)
			(size 1.8034 0.508)
			(layers "F.Cu" "F.Mask" "F.Paste")
			(net "GND")
		)
		(pad "124" smd rect
			(at 0 109.650022 90)
			(size 1.8034 0.508)
			(layers "F.Cu" "F.Mask" "F.Paste")
			(net "M_A_DQ<55>")
		)
		(pad "125" smd rect
			(at 0 110.499906 90)
			(size 1.8034 0.508)
			(layers "F.Cu" "F.Mask" "F.Paste")
			(net "GND")
		)
		(pad "126" smd rect
			(at 0 111.350044 90)
			(size 1.8034 0.508)
			(layers "F.Cu" "F.Mask" "F.Paste")
			(net "M_A_DQ<51>")
		)
		(pad "127" smd rect
			(at 0 112.199928 90)
			(size 1.8034 0.508)
			(layers "F.Cu" "F.Mask" "F.Paste")
			(net "GND")
		)
		(pad "128" smd rect
			(at 0 113.050066 90)
			(size 1.8034 0.508)
			(layers "F.Cu" "F.Mask" "F.Paste")
			(net "M_A_DQ<61>")
		)
		(pad "129" smd rect
			(at 0 113.89995 90)
			(size 1.8034 0.508)
			(layers "F.Cu" "F.Mask" "F.Paste")
			(net "GND")
		)
		(pad "130" smd rect
			(at 0 114.750088 90)
			(size 1.8034 0.508)
			(layers "F.Cu" "F.Mask" "F.Paste")
			(net "M_A_DQ<57>")
		)
		(pad "131" smd rect
			(at 0 115.599972 90)
			(size 1.8034 0.508)
			(layers "F.Cu" "F.Mask" "F.Paste")
			(net "GND")
		)
		(pad "132" smd rect
			(at 0 116.45011 90)
			(size 1.8034 0.508)
			(layers "F.Cu" "F.Mask" "F.Paste")
			(net "M_A_DQS_DP<16>")
		)
		(pad "133" smd rect
			(at 0 117.299994 90)
			(size 1.8034 0.508)
			(layers "F.Cu" "F.Mask" "F.Paste")
			(net "M_A_DQS_DN<16>")
		)
		(pad "134" smd rect
			(at 0 118.149878 90)
			(size 1.8034 0.508)
			(layers "F.Cu" "F.Mask" "F.Paste")
			(net "GND")
		)
		(pad "135" smd rect
			(at 0 119.000016 90)
			(size 1.8034 0.508)
			(layers "F.Cu" "F.Mask" "F.Paste")
			(net "M_A_DQ<63>")
		)
		(pad "136" smd rect
			(at 0 119.8499 90)
			(size 1.8034 0.508)
			(layers "F.Cu" "F.Mask" "F.Paste")
			(net "GND")
		)
		(pad "137" smd rect
			(at 0 120.700038 90)
			(size 1.8034 0.508)
			(layers "F.Cu" "F.Mask" "F.Paste")
			(net "M_A_DQ<59>")
		)
		(pad "138" smd rect
			(at 0 121.549922 90)
			(size 1.8034 0.508)
			(layers "F.Cu" "F.Mask" "F.Paste")
			(net "GND")
		)
		(pad "139" smd rect
			(at 0 122.40006 90)
			(size 1.8034 0.508)
			(layers "F.Cu" "F.Mask" "F.Paste")
			(net "GND")
		)
		(pad "140" smd rect
			(at 0 123.249944 90)
			(size 1.8034 0.508)
			(layers "F.Cu" "F.Mask" "F.Paste")
			(net "GND")
		)
		(pad "141" smd rect
			(at 0 124.100082 90)
			(size 1.8034 0.508)
			(layers "F.Cu" "F.Mask" "F.Paste")
			(net "SMB_DDR_ABC_VPP_SCL")
		)
		(pad "142" smd rect
			(at 0 124.949966 90)
			(size 1.8034 0.508)
			(layers "F.Cu" "F.Mask" "F.Paste")
			(net "PVPP_ABC")
		)
		(pad "143" smd rect
			(at 0 125.800104 90)
			(size 1.8034 0.508)
			(layers "F.Cu" "F.Mask" "F.Paste")
			(net "PVPP_ABC")
		)
		(pad "144" smd rect
			(at 0 126.649988 90)
			(size 1.8034 0.508)
			(layers "F.Cu" "F.Mask" "F.Paste")
			(net "TP_CH_A_DIMM_A0_RFU_2")
		)
		(pad "145" smd rect
			(at 4.59994 0 90)
			(size 1.8034 0.508)
			(layers "F.Cu" "F.Mask" "F.Paste")
			(net "P12V_NVDIMM_ABC")
		)
		(pad "146" smd rect
			(at 4.59994 0.849884 90)
			(size 1.8034 0.508)
			(layers "F.Cu" "F.Mask" "F.Paste")
			(net "M_A_VREF")
		)
		(pad "147" smd rect
			(at 4.59994 1.700022 90)
			(size 1.8034 0.508)
			(layers "F.Cu" "F.Mask" "F.Paste")
			(net "GND")
		)
		(pad "148" smd rect
			(at 4.59994 2.549906 90)
			(size 1.8034 0.508)
			(layers "F.Cu" "F.Mask" "F.Paste")
			(net "M_A_DQ<4>")
		)
		(pad "149" smd rect
			(at 4.59994 3.400044 90)
			(size 1.8034 0.508)
			(layers "F.Cu" "F.Mask" "F.Paste")
			(net "GND")
		)
		(pad "150" smd rect
			(at 4.59994 4.249928 90)
			(size 1.8034 0.508)
			(layers "F.Cu" "F.Mask" "F.Paste")
			(net "M_A_DQ<0>")
		)
		(pad "151" smd rect
			(at 4.59994 5.100066 90)
			(size 1.8034 0.508)
			(layers "F.Cu" "F.Mask" "F.Paste")
			(net "GND")
		)
		(pad "152" smd rect
			(at 4.59994 5.94995 90)
			(size 1.8034 0.508)
			(layers "F.Cu" "F.Mask" "F.Paste")
			(net "M_A_DQS_DN<0>")
		)
		(pad "153" smd rect
			(at 4.59994 6.800088 90)
			(size 1.8034 0.508)
			(layers "F.Cu" "F.Mask" "F.Paste")
			(net "M_A_DQS_DP<0>")
		)
		(pad "154" smd rect
			(at 4.59994 7.649972 90)
			(size 1.8034 0.508)
			(layers "F.Cu" "F.Mask" "F.Paste")
			(net "GND")
		)
		(pad "155" smd rect
			(at 4.59994 8.50011 90)
			(size 1.8034 0.508)
			(layers "F.Cu" "F.Mask" "F.Paste")
			(net "M_A_DQ<6>")
		)
		(pad "156" smd rect
			(at 4.59994 9.349994 90)
			(size 1.8034 0.508)
			(layers "F.Cu" "F.Mask" "F.Paste")
			(net "GND")
		)
		(pad "157" smd rect
			(at 4.59994 10.199878 90)
			(size 1.8034 0.508)
			(layers "F.Cu" "F.Mask" "F.Paste")
			(net "M_A_DQ<2>")
		)
		(pad "158" smd rect
			(at 4.59994 11.050016 90)
			(size 1.8034 0.508)
			(layers "F.Cu" "F.Mask" "F.Paste")
			(net "GND")
		)
		(pad "159" smd rect
			(at 4.59994 11.8999 90)
			(size 1.8034 0.508)
			(layers "F.Cu" "F.Mask" "F.Paste")
			(net "M_A_DQ<12>")
		)
		(pad "160" smd rect
			(at 4.59994 12.750038 90)
			(size 1.8034 0.508)
			(layers "F.Cu" "F.Mask" "F.Paste")
			(net "GND")
		)
		(pad "161" smd rect
			(at 4.59994 13.599922 90)
			(size 1.8034 0.508)
			(layers "F.Cu" "F.Mask" "F.Paste")
			(net "M_A_DQ<8>")
		)
		(pad "162" smd rect
			(at 4.59994 14.45006 90)
			(size 1.8034 0.508)
			(layers "F.Cu" "F.Mask" "F.Paste")
			(net "GND")
		)
		(pad "163" smd rect
			(at 4.59994 15.299944 90)
			(size 1.8034 0.508)
			(layers "F.Cu" "F.Mask" "F.Paste")
			(net "M_A_DQS_DN<1>")
		)
		(pad "164" smd rect
			(at 4.59994 16.150082 90)
			(size 1.8034 0.508)
			(layers "F.Cu" "F.Mask" "F.Paste")
			(net "M_A_DQS_DP<1>")
		)
		(pad "165" smd rect
			(at 4.59994 16.999966 90)
			(size 1.8034 0.508)
			(layers "F.Cu" "F.Mask" "F.Paste")
			(net "GND")
		)
		(pad "166" smd rect
			(at 4.59994 17.850104 90)
			(size 1.8034 0.508)
			(layers "F.Cu" "F.Mask" "F.Paste")
			(net "M_A_DQ<14>")
		)
		(pad "167" smd rect
			(at 4.59994 18.699988 90)
			(size 1.8034 0.508)
			(layers "F.Cu" "F.Mask" "F.Paste")
			(net "GND")
		)
		(pad "168" smd rect
			(at 4.59994 19.550126 90)
			(size 1.8034 0.508)
			(layers "F.Cu" "F.Mask" "F.Paste")
			(net "M_A_DQ<10>")
		)
		(pad "169" smd rect
			(at 4.59994 20.40001 90)
			(size 1.8034 0.508)
			(layers "F.Cu" "F.Mask" "F.Paste")
			(net "GND")
		)
		(pad "170" smd rect
			(at 4.59994 21.249894 90)
			(size 1.8034 0.508)
			(layers "F.Cu" "F.Mask" "F.Paste")
			(net "M_A_DQ<20>")
		)
		(pad "171" smd rect
			(at 4.59994 22.100032 90)
			(size 1.8034 0.508)
			(layers "F.Cu" "F.Mask" "F.Paste")
			(net "GND")
		)
		(pad "172" smd rect
			(at 4.59994 22.949916 90)
			(size 1.8034 0.508)
			(layers "F.Cu" "F.Mask" "F.Paste")
			(net "M_A_DQ<16>")
		)
		(pad "173" smd rect
			(at 4.59994 23.800054 90)
			(size 1.8034 0.508)
			(layers "F.Cu" "F.Mask" "F.Paste")
			(net "GND")
		)
		(pad "174" smd rect
			(at 4.59994 24.649938 90)
			(size 1.8034 0.508)
			(layers "F.Cu" "F.Mask" "F.Paste")
			(net "M_A_DQS_DN<2>")
		)
		(pad "175" smd rect
			(at 4.59994 25.500076 90)
			(size 1.8034 0.508)
			(layers "F.Cu" "F.Mask" "F.Paste")
			(net "M_A_DQS_DP<2>")
		)
		(pad "176" smd rect
			(at 4.59994 26.34996 90)
			(size 1.8034 0.508)
			(layers "F.Cu" "F.Mask" "F.Paste")
			(net "GND")
		)
		(pad "177" smd rect
			(at 4.59994 27.200098 90)
			(size 1.8034 0.508)
			(layers "F.Cu" "F.Mask" "F.Paste")
			(net "M_A_DQ<22>")
		)
		(pad "178" smd rect
			(at 4.59994 28.049982 90)
			(size 1.8034 0.508)
			(layers "F.Cu" "F.Mask" "F.Paste")
			(net "GND")
		)
		(pad "179" smd rect
			(at 4.59994 28.90012 90)
			(size 1.8034 0.508)
			(layers "F.Cu" "F.Mask" "F.Paste")
			(net "M_A_DQ<18>")
		)
		(pad "180" smd rect
			(at 4.59994 29.750004 90)
			(size 1.8034 0.508)
			(layers "F.Cu" "F.Mask" "F.Paste")
			(net "GND")
		)
		(pad "181" smd rect
			(at 4.59994 30.599888 90)
			(size 1.8034 0.508)
			(layers "F.Cu" "F.Mask" "F.Paste")
			(net "M_A_DQ<28>")
		)
		(pad "182" smd rect
			(at 4.59994 31.450026 90)
			(size 1.8034 0.508)
			(layers "F.Cu" "F.Mask" "F.Paste")
			(net "GND")
		)
		(pad "183" smd rect
			(at 4.59994 32.29991 90)
			(size 1.8034 0.508)
			(layers "F.Cu" "F.Mask" "F.Paste")
			(net "M_A_DQ<24>")
		)
		(pad "184" smd rect
			(at 4.59994 33.150048 90)
			(size 1.8034 0.508)
			(layers "F.Cu" "F.Mask" "F.Paste")
			(net "GND")
		)
		(pad "185" smd rect
			(at 4.59994 33.999932 90)
			(size 1.8034 0.508)
			(layers "F.Cu" "F.Mask" "F.Paste")
			(net "M_A_DQS_DN<3>")
		)
		(pad "186" smd rect
			(at 4.59994 34.85007 90)
			(size 1.8034 0.508)
			(layers "F.Cu" "F.Mask" "F.Paste")
			(net "M_A_DQS_DP<3>")
		)
		(pad "187" smd rect
			(at 4.59994 35.699954 90)
			(size 1.8034 0.508)
			(layers "F.Cu" "F.Mask" "F.Paste")
			(net "GND")
		)
		(pad "188" smd rect
			(at 4.59994 36.550092 90)
			(size 1.8034 0.508)
			(layers "F.Cu" "F.Mask" "F.Paste")
			(net "M_A_DQ<30>")
		)
		(pad "189" smd rect
			(at 4.59994 37.399976 90)
			(size 1.8034 0.508)
			(layers "F.Cu" "F.Mask" "F.Paste")
			(net "GND")
		)
		(pad "190" smd rect
			(at 4.59994 38.250114 90)
			(size 1.8034 0.508)
			(layers "F.Cu" "F.Mask" "F.Paste")
			(net "M_A_DQ<26>")
		)
		(pad "191" smd rect
			(at 4.59994 39.099998 90)
			(size 1.8034 0.508)
			(layers "F.Cu" "F.Mask" "F.Paste")
			(net "GND")
		)
		(pad "192" smd rect
			(at 4.59994 39.949882 90)
			(size 1.8034 0.508)
			(layers "F.Cu" "F.Mask" "F.Paste")
			(net "M_A_ECC<4>")
		)
		(pad "193" smd rect
			(at 4.59994 40.80002 90)
			(size 1.8034 0.508)
			(layers "F.Cu" "F.Mask" "F.Paste")
			(net "GND")
		)
		(pad "194" smd rect
			(at 4.59994 41.649904 90)
			(size 1.8034 0.508)
			(layers "F.Cu" "F.Mask" "F.Paste")
			(net "M_A_ECC<0>")
		)
		(pad "195" smd rect
			(at 4.59994 42.500042 90)
			(size 1.8034 0.508)
			(layers "F.Cu" "F.Mask" "F.Paste")
			(net "GND")
		)
		(pad "196" smd rect
			(at 4.59994 43.349926 90)
			(size 1.8034 0.508)
			(layers "F.Cu" "F.Mask" "F.Paste")
			(net "M_A_DQS_DN<8>")
		)
		(pad "197" smd rect
			(at 4.59994 44.200064 90)
			(size 1.8034 0.508)
			(layers "F.Cu" "F.Mask" "F.Paste")
			(net "M_A_DQS_DP<8>")
		)
		(pad "198" smd rect
			(at 4.59994 45.049948 90)
			(size 1.8034 0.508)
			(layers "F.Cu" "F.Mask" "F.Paste")
			(net "GND")
		)
		(pad "199" smd rect
			(at 4.59994 45.900086 90)
			(size 1.8034 0.508)
			(layers "F.Cu" "F.Mask" "F.Paste")
			(net "M_A_ECC<6>")
		)
		(pad "200" smd rect
			(at 4.59994 46.74997 90)
			(size 1.8034 0.508)
			(layers "F.Cu" "F.Mask" "F.Paste")
			(net "GND")
		)
		(pad "201" smd rect
			(at 4.59994 47.600108 90)
			(size 1.8034 0.508)
			(layers "F.Cu" "F.Mask" "F.Paste")
			(net "M_A_ECC<2>")
		)
		(pad "202" smd rect
			(at 4.59994 48.449992 90)
			(size 1.8034 0.508)
			(layers "F.Cu" "F.Mask" "F.Paste")
			(net "GND")
		)
		(pad "203" smd rect
			(at 4.59994 49.299876 90)
			(size 1.8034 0.508)
			(layers "F.Cu" "F.Mask" "F.Paste")
			(net "M_A_CKE<1>")
		)
		(pad "204" smd rect
			(at 4.59994 50.150014 90)
			(size 1.8034 0.508)
			(layers "F.Cu" "F.Mask" "F.Paste")
			(net "PVDDQ_ABC")
		)
		(pad "205" smd rect
			(at 4.59994 50.999898 90)
			(size 1.8034 0.508)
			(layers "F.Cu" "F.Mask" "F.Paste")
			(net "TP_CH_A_DIMM_A0_RFU_0")
		)
		(pad "206" smd rect
			(at 4.59994 51.850036 90)
			(size 1.8034 0.508)
			(layers "F.Cu" "F.Mask" "F.Paste")
			(net "PVDDQ_ABC")
		)
		(pad "207" smd rect
			(at 4.59994 52.69992 90)
			(size 1.8034 0.508)
			(layers "F.Cu" "F.Mask" "F.Paste")
			(net "M_A_BG<1>")
		)
		(pad "208" smd rect
			(at 4.59994 53.550058 90)
			(size 1.8034 0.508)
			(layers "F.Cu" "F.Mask" "F.Paste")
			(net "M_A_ALERT_N")
		)
		(pad "209" smd rect
			(at 4.59994 54.399942 90)
			(size 1.8034 0.508)
			(layers "F.Cu" "F.Mask" "F.Paste")
			(net "PVDDQ_ABC")
		)
		(pad "210" smd rect
			(at 4.59994 55.25008 90)
			(size 1.8034 0.508)
			(layers "F.Cu" "F.Mask" "F.Paste")
			(net "M_A_MA<11>")
		)
		(pad "211" smd rect
			(at 4.59994 56.099964 90)
			(size 1.8034 0.508)
			(layers "F.Cu" "F.Mask" "F.Paste")
			(net "M_A_MA<7>")
		)
		(pad "212" smd rect
			(at 4.59994 56.950102 90)
			(size 1.8034 0.508)
			(layers "F.Cu" "F.Mask" "F.Paste")
			(net "PVDDQ_ABC")
		)
		(pad "213" smd rect
			(at 4.59994 57.799986 90)
			(size 1.8034 0.508)
			(layers "F.Cu" "F.Mask" "F.Paste")
			(net "M_A_MA<5>")
		)
		(pad "214" smd rect
			(at 4.59994 58.650124 90)
			(size 1.8034 0.508)
			(layers "F.Cu" "F.Mask" "F.Paste")
			(net "M_A_MA<4>")
		)
		(pad "215" smd rect
			(at 4.59994 59.500008 90)
			(size 1.8034 0.508)
			(layers "F.Cu" "F.Mask" "F.Paste")
			(net "PVDDQ_ABC")
		)
		(pad "216" smd rect
			(at 4.59994 60.349892 90)
			(size 1.8034 0.508)
			(layers "F.Cu" "F.Mask" "F.Paste")
			(net "M_A_MA<2>")
		)
		(pad "217" smd rect
			(at 4.59994 61.20003 90)
			(size 1.8034 0.508)
			(layers "F.Cu" "F.Mask" "F.Paste")
			(net "PVDDQ_ABC")
		)
		(pad "218" smd rect
			(at 4.59994 62.049914 90)
			(size 1.8034 0.508)
			(layers "F.Cu" "F.Mask" "F.Paste")
			(net "M_A_CLK_DP<1>")
		)
		(pad "219" smd rect
			(at 4.59994 62.900052 90)
			(size 1.8034 0.508)
			(layers "F.Cu" "F.Mask" "F.Paste")
			(net "M_A_CLK_DN<1>")
		)
		(pad "220" smd rect
			(at 4.59994 63.749936 90)
			(size 1.8034 0.508)
			(layers "F.Cu" "F.Mask" "F.Paste")
			(net "PVDDQ_ABC")
		)
		(pad "221" smd rect
			(at 4.59994 64.600074 90)
			(size 1.8034 0.508)
			(layers "F.Cu" "F.Mask" "F.Paste")
			(net "PVTT_ABC")
		)
		(pad "222" smd rect
			(at 4.59994 70.550024 90)
			(size 1.8034 0.508)
			(layers "F.Cu" "F.Mask" "F.Paste")
			(net "M_A_PAR")
		)
		(pad "223" smd rect
			(at 4.59994 71.399908 90)
			(size 1.8034 0.508)
			(layers "F.Cu" "F.Mask" "F.Paste")
			(net "PVDDQ_ABC")
		)
		(pad "224" smd rect
			(at 4.59994 72.250046 90)
			(size 1.8034 0.508)
			(layers "F.Cu" "F.Mask" "F.Paste")
			(net "M_A_BA<1>")
		)
		(pad "225" smd rect
			(at 4.59994 73.09993 90)
			(size 1.8034 0.508)
			(layers "F.Cu" "F.Mask" "F.Paste")
			(net "M_A_MA<10>")
		)
		(pad "226" smd rect
			(at 4.59994 73.950068 90)
			(size 1.8034 0.508)
			(layers "F.Cu" "F.Mask" "F.Paste")
			(net "PVDDQ_ABC")
		)
		(pad "227" smd rect
			(at 4.59994 74.799952 90)
			(size 1.8034 0.508)
			(layers "F.Cu" "F.Mask" "F.Paste")
			(net "TP_CH_A_DIMM_A0_RFU_1")
		)
		(pad "228" smd rect
			(at 4.59994 75.65009 90)
			(size 1.8034 0.508)
			(layers "F.Cu" "F.Mask" "F.Paste")
			(net "M_A_MA<14>")
		)
		(pad "229" smd rect
			(at 4.59994 76.499974 90)
			(size 1.8034 0.508)
			(layers "F.Cu" "F.Mask" "F.Paste")
			(net "PVDDQ_ABC")
		)
		(pad "230" smd rect
			(at 4.59994 77.350112 90)
			(size 1.8034 0.508)
			(layers "F.Cu" "F.Mask" "F.Paste")
			(net "FM_ADR_COMPLETE_ABC_N")
		)
		(pad "231" smd rect
			(at 4.59994 78.199996 90)
			(size 1.8034 0.508)
			(layers "F.Cu" "F.Mask" "F.Paste")
			(net "PVDDQ_ABC")
		)
		(pad "232" smd rect
			(at 4.59994 79.04988 90)
			(size 1.8034 0.508)
			(layers "F.Cu" "F.Mask" "F.Paste")
			(net "M_A_MA<13>")
		)
		(pad "233" smd rect
			(at 4.59994 79.900018 90)
			(size 1.8034 0.508)
			(layers "F.Cu" "F.Mask" "F.Paste")
			(net "PVDDQ_ABC")
		)
		(pad "234" smd rect
			(at 4.59994 80.749902 90)
			(size 1.8034 0.508)
			(layers "F.Cu" "F.Mask" "F.Paste")
			(net "M_A_MA<17>")
		)
		(pad "235" smd rect
			(at 4.59994 81.60004 90)
			(size 1.8034 0.508)
			(layers "F.Cu" "F.Mask" "F.Paste")
			(net "M_A_C<2>")
		)
		(pad "236" smd rect
			(at 4.59994 82.449924 90)
			(size 1.8034 0.508)
			(layers "F.Cu" "F.Mask" "F.Paste")
			(net "PVDDQ_ABC")
		)
		(pad "237" smd rect
			(at 4.59994 83.300062 90)
			(size 1.8034 0.508)
			(layers "F.Cu" "F.Mask" "F.Paste")
			(net "M_A_CS_N<3>")
		)
		(pad "238" smd rect
			(at 4.59994 84.149946 90)
			(size 1.8034 0.508)
			(layers "F.Cu" "F.Mask" "F.Paste")
			(net "GND")
		)
		(pad "239" smd rect
			(at 4.59994 85.000084 90)
			(size 1.8034 0.508)
			(layers "F.Cu" "F.Mask" "F.Paste")
			(net "GND")
		)
		(pad "240" smd rect
			(at 4.59994 85.849968 90)
			(size 1.8034 0.508)
			(layers "F.Cu" "F.Mask" "F.Paste")
			(net "M_A_DQ<36>")
		)
	)
)
